# T6G (Grand Teton) — schematic netlist excerpt (pin names and nets, part order shuffled) for the footprints in the layout excerpt that follows; sources: Cadence DE-HDL packaged netlist, KiCad conversion of 04192023_DAF0TMB3IC0_F0TG_MB_C_brd_V02_OCP.brd

PC6636_2  Q_CAP  22UF 16V 20% X6S  pkg C0805  page 365 : A = SW_P12V_AUX_P0V9_RETIMER_CPU1_FLT ; B = GND
C613  Q_CAP  1UF 4V 20% X6S  pkg 0201  page 290 : A = P0V9_CPU0_RT1_2A ; B = GND
PR99  Q_RES  2.2 1% CHIP  pkg 0402LF  page 205 : A = PVDDCR_CPU1_P0_PVCC ; B = PVDDIO_P0_VCC2
C393  Q_CAP  0.1UF 10V 10% X7S  pkg C0201  page 345 : A = P0V9_CPU1_RT2_2A ; B = GND

(kicad_pcb
	(version 20260206)
	(generator "pcbnew")
	(generator_version "10.0")
	(general
		(thickness 1.6)
		(legacy_teardrops no)
	)
	(paper "A4")
	(title_block
		(title "04192023_DAF0TMB3IC0_F0TG_MB_C_brd_V02_OCP.brd")
		(comment 1 "Grand Teton / footprints 7062-7065 of 8354")
	)
	(layers
		(0 "F.Cu" signal "TOP")
		(4 "In1.Cu" signal "GND")
		(6 "In2.Cu" signal "IN1")
		(8 "In3.Cu" signal "GND1")
		(10 "In4.Cu" signal "IN2")
		(12 "In5.Cu" signal "GND2")
		(14 "In6.Cu" signal "IN3")
		(16 "In7.Cu" signal "GND3")
		(18 "In8.Cu" signal "VCC")
		(20 "In9.Cu" signal "VCC1")
		(22 "In10.Cu" signal "GND4")
		(24 "In11.Cu" signal "IN4")
		(26 "In12.Cu" signal "GND5")
		(28 "In13.Cu" signal "IN5")
		(30 "In14.Cu" signal "GND6")
		(32 "In15.Cu" signal "IN6")
		(34 "In16.Cu" signal "GND7")
		(2 "B.Cu" signal "BOTTOM")
		(9 "F.Adhes" user "F.Adhesive")
		(11 "B.Adhes" user "B.Adhesive")
		(13 "F.Paste" user "Package Geometry/Pastemask Top")
		(15 "B.Paste" user "Package Geometry/Pastemask Bottom")
		(5 "F.SilkS" user "Ref Des/Silkscreen Top")
		(7 "B.SilkS" user "Ref Des/Silkscreen Bottom")
		(1 "F.Mask" user "Board Geometry/Soldermask Top")
		(3 "B.Mask" user "Board Geometry/Soldermask Bottom")
		(17 "Dwgs.User" user "User.Drawings")
		(19 "Cmts.User" user "User.Comments")
		(21 "Eco1.User" user "User.Eco1")
		(23 "Eco2.User" user "User.Eco2")
		(25 "Edge.Cuts" user "Board Geometry/Outline")
		(27 "Margin" user)
		(31 "F.CrtYd" user "Package Geometry/Place Bound Top")
		(29 "B.CrtYd" user "Package Geometry/Place Bound Bottom")
		(35 "F.Fab" user "Ref Des/Assembly Top")
		(33 "B.Fab" user "Ref Des/Assembly Bottom")
	)
	(footprint ""
		(layer "B.Cu")
		(at 351.506028 -395.148562 90)
		(property "Reference" "C613"
			(at 0 0 90)
			(layer "B.SilkS")
			(hide yes)
			(effects
				(font
					(size 1.27 1.27)
				)
				(justify mirror)
			)
		)
		(property "Value" ""
			(at 0 0 90)
			(layer "B.Fab")
			(effects
				(font
					(size 1.27 1.27)
				)
				(justify mirror)
			)
		)
		(duplicate_pad_numbers_are_jumpers no)
		(fp_line
			(start 0.299974 -0.150114)
			(end -0.299974 -0.150114)
			(stroke
				(width 0.1)
				(type default)
			)
			(layer "B.Fab")
		)
		(fp_line
			(start -0.299974 -0.150114)
			(end -0.299974 0.150114)
			(stroke
				(width 0.1)
				(type default)
			)
			(layer "B.Fab")
		)
		(fp_line
			(start 0.299974 0.150114)
			(end 0.299974 -0.150114)
			(stroke
				(width 0.1)
				(type default)
			)
			(layer "B.Fab")
		)
		(fp_line
			(start -0.299974 0.150114)
			(end 0.299974 0.150114)
			(stroke
				(width 0.1)
				(type default)
			)
			(layer "B.Fab")
		)
		(pad "1" smd rect
			(at 0.2667 0 270)
			(size 0.3048 0.381)
			(layers "B.Cu" "B.Mask" "B.Paste")
			(net "P0V9_CPU0_RT1_2A")
		)
		(pad "2" smd rect
			(at -0.2667 0 270)
			(size 0.3048 0.381)
			(layers "B.Cu" "B.Mask" "B.Paste")
			(net "GND")
		)
	)
	(footprint ""
		(layer "B.Cu")
		(at 26.641298 -388.637272 90)
		(property "Reference" "PC6636_2"
			(at 0 0 90)
			(layer "B.SilkS")
			(hide yes)
			(effects
				(font
					(size 1.27 1.27)
				)
				(justify mirror)
			)
		)
		(property "Value" ""
			(at 0 0 90)
			(layer "B.Fab")
			(effects
				(font
					(size 1.27 1.27)
				)
				(justify mirror)
			)
		)
		(duplicate_pad_numbers_are_jumpers no)
		(fp_line
			(start 1.524 -0.762)
			(end -1.524 -0.762)
			(stroke
				(width 0.1524)
				(type default)
			)
			(layer "B.SilkS")
		)
		(fp_line
			(start -1.524 -0.762)
			(end -1.524 0.762)
			(stroke
				(width 0.1524)
				(type default)
			)
			(layer "B.SilkS")
		)
		(fp_line
			(start 1.524 0.762)
			(end 1.524 -0.762)
			(stroke
				(width 0.1524)
				(type default)
			)
			(layer "B.SilkS")
		)
		(fp_line
			(start -1.524 0.762)
			(end 1.524 0.762)
			(stroke
				(width 0.1524)
				(type default)
			)
			(layer "B.SilkS")
		)
		(fp_line
			(start 1.1049 -0.724916)
			(end 1.1049 0.724916)
			(stroke
				(width 0.1)
				(type default)
			)
			(layer "B.Fab")
		)
		(fp_line
			(start -1.1049 -0.724916)
			(end 1.1049 -0.724916)
			(stroke
				(width 0.1)
				(type default)
			)
			(layer "B.Fab")
		)
		(fp_line
			(start 1.1049 0.724916)
			(end -1.1049 0.724916)
			(stroke
				(width 0.1)
				(type default)
			)
			(layer "B.Fab")
		)
		(fp_line
			(start -1.1049 0.724916)
			(end -1.1049 -0.724916)
			(stroke
				(width 0.1)
				(type default)
			)
			(layer "B.Fab")
		)
		(pad "1" smd rect
			(at 0.889 0 90)
			(size 1.016 1.27)
			(layers "B.Cu" "B.Mask" "B.Paste")
			(net "SW_P12V_AUX_P0V9_RETIMER_CPU1_FLT")
		)
		(pad "2" smd rect
			(at -0.889 0 90)
			(size 1.016 1.27)
			(layers "B.Cu" "B.Mask" "B.Paste")
			(net "GND")
		)
	)
	(footprint ""
		(layer "B.Cu")
		(at 289.697414 -347.77553 -90)
		(property "Reference" "PR99"
			(at 0 0 90)
			(layer "B.SilkS")
			(hide yes)
			(effects
				(font
					(size 1.27 1.27)
				)
				(justify mirror)
			)
		)
		(property "Value" ""
			(at 0 0 90)
			(layer "B.Fab")
			(effects
				(font
					(size 1.27 1.27)
				)
				(justify mirror)
			)
		)
		(duplicate_pad_numbers_are_jumpers no)
		(fp_line
			(start -0.7874 0.4064)
			(end 0.7874 0.4064)
			(stroke
				(width 0.1524)
				(type default)
			)
			(layer "B.SilkS")
		)
		(fp_line
			(start 0.7874 0.4064)
			(end 0.7874 -0.4064)
			(stroke
				(width 0.1524)
				(type default)
			)
			(layer "B.SilkS")
		)
		(fp_line
			(start -0.7874 -0.4064)
			(end -0.7874 0.4064)
			(stroke
				(width 0.1524)
				(type default)
			)
			(layer "B.SilkS")
		)
		(fp_line
			(start 0.7874 -0.4064)
			(end -0.7874 -0.4064)
			(stroke
				(width 0.1524)
				(type default)
			)
			(layer "B.SilkS")
		)
		(fp_line
			(start -0.67945 0.3048)
			(end -0.120396 0.3048)
			(stroke
				(width 0.1)
				(type default)
			)
			(layer "B.Fab")
		)
		(fp_line
			(start -0.120396 0.3048)
			(end -0.120396 0.2794)
			(stroke
				(width 0.1)
				(type default)
			)
			(layer "B.Fab")
		)
		(fp_line
			(start 0.12065 0.3048)
			(end 0.67945 0.3048)
			(stroke
				(width 0.1)
				(type default)
			)
			(layer "B.Fab")
		)
		(fp_line
			(start 0.67945 0.3048)
			(end 0.67945 -0.305054)
			(stroke
				(width 0.1)
				(type default)
			)
			(layer "B.Fab")
		)
		(fp_line
			(start -0.120396 0.2794)
			(end 0.12065 0.2794)
			(stroke
				(width 0.1)
				(type default)
			)
			(layer "B.Fab")
		)
		(fp_line
			(start 0.12065 0.2794)
			(end 0.12065 0.3048)
			(stroke
				(width 0.1)
				(type default)
			)
			(layer "B.Fab")
		)
		(fp_line
			(start -0.12065 -0.2794)
			(end -0.12065 -0.3048)
			(stroke
				(width 0.1)
				(type default)
			)
			(layer "B.Fab")
		)
		(fp_line
			(start 0.12065 -0.2794)
			(end -0.12065 -0.2794)
			(stroke
				(width 0.1)
				(type default)
			)
			(layer "B.Fab")
		)
		(fp_line
			(start -0.67945 -0.3048)
			(end -0.67945 0.3048)
			(stroke
				(width 0.1)
				(type default)
			)
			(layer "B.Fab")
		)
		(fp_line
			(start -0.12065 -0.3048)
			(end -0.67945 -0.3048)
			(stroke
				(width 0.1)
				(type default)
			)
			(layer "B.Fab")
		)
		(fp_line
			(start 0.12065 -0.305054)
			(end 0.12065 -0.2794)
			(stroke
				(width 0.1)
				(type default)
			)
			(layer "B.Fab")
		)
		(fp_line
			(start 0.67945 -0.305054)
			(end 0.12065 -0.305054)
			(stroke
				(width 0.1)
				(type default)
			)
			(layer "B.Fab")
		)
		(pad "1" smd circle
			(at 0.40005 0 90)
			(size 0 0)
			(layers "B.Cu" "B.Mask" "B.Paste")
			(net "PVDDCR_CPU1_P0_PVCC")
		)
		(pad "2" smd circle
			(at -0.40005 0 90)
			(size 0 0)
			(layers "B.Cu" "B.Mask" "B.Paste")
			(net "PVDDIO_P0_VCC2")
		)
	)
	(footprint ""
		(layer "B.Cu")
		(at 144.727676 -388.609078 90)
		(property "Reference" "C393"
			(at 0 0 90)
			(layer "B.SilkS")
			(hide yes)
			(effects
				(font
					(size 1.27 1.27)
				)
				(justify mirror)
			)
		)
		(property "Value" ""
			(at 0 0 90)
			(layer "B.Fab")
			(effects
				(font
					(size 1.27 1.27)
				)
				(justify mirror)
			)
		)
		(duplicate_pad_numbers_are_jumpers no)
		(fp_line
			(start 0.299974 -0.150114)
			(end -0.299974 -0.150114)
			(stroke
				(width 0.1)
				(type default)
			)
			(layer "B.Fab")
		)
		(fp_line
			(start -0.299974 -0.150114)
			(end -0.299974 0.150114)
			(stroke
				(width 0.1)
				(type default)
			)
			(layer "B.Fab")
		)
		(fp_line
			(start 0.299974 0.150114)
			(end 0.299974 -0.150114)
			(stroke
				(width 0.1)
				(type default)
			)
			(layer "B.Fab")
		)
		(fp_line
			(start -0.299974 0.150114)
			(end 0.299974 0.150114)
			(stroke
				(width 0.1)
				(type default)
			)
			(layer "B.Fab")
		)
		(pad "1" smd rect
			(at 0.2667 0 270)
			(size 0.3048 0.381)
			(layers "B.Cu" "B.Mask" "B.Paste")
			(net "P0V9_CPU1_RT2_2A")
		)
		(pad "2" smd rect
			(at -0.2667 0 270)
			(size 0.3048 0.381)
			(layers "B.Cu" "B.Mask" "B.Paste")
			(net "GND")
		)
	)
)
